(kicad_pcb
	(version 20260206)
	(generator "pcbnew")
	(generator_version "10.0")
	(general
		(thickness 1.6)
		(legacy_teardrops no)
	)
	(paper "A4")
	(title_block
		(title "Bryce Canyon_IOM_IOC_16318-2_OCP.brd")
		(comment 1 "Bryce Canyon / footprints 731-738 of 1605")
	)
	(layers
		(0 "F.Cu" signal "TOP")
		(4 "In1.Cu" signal "L2GND")
		(6 "In2.Cu" signal "L3")
		(8 "In3.Cu" signal "L4VCC")
		(10 "In4.Cu" signal "L5VCC")
		(12 "In5.Cu" signal "L6")
		(14 "In6.Cu" signal "L7GND")
		(2 "B.Cu" signal "BOTTOM")
		(9 "F.Adhes" user "F.Adhesive")
		(11 "B.Adhes" user "B.Adhesive")
		(13 "F.Paste" user "Package Geometry/Pastemask Top")
		(15 "B.Paste" user "Package Geometry/Pastemask Bottom")
		(5 "F.SilkS" user "Ref Des/Silkscreen Top")
		(7 "B.SilkS" user "Ref Des/Silkscreen Bottom")
		(1 "F.Mask" user "Board Geometry/Soldermask Top")
		(3 "B.Mask" user "Board Geometry/Soldermask Bottom")
		(17 "Dwgs.User" user "User.Drawings")
		(19 "Cmts.User" user "User.Comments")
		(21 "Eco1.User" user "User.Eco1")
		(23 "Eco2.User" user "User.Eco2")
		(25 "Edge.Cuts" user "Board Geometry/Outline")
		(27 "Margin" user)
		(31 "F.CrtYd" user "Package Geometry/Place Bound Top")
		(29 "B.CrtYd" user "Package Geometry/Place Bound Bottom")
		(35 "F.Fab" user "Ref Des/Assembly Top")
		(33 "B.Fab" user "Ref Des/Assembly Bottom")
	)
	(footprint ""
		(layer "F.Cu")
		(at 19.752564 -160.971484 180)
		(property "Reference" "R529"
			(at 0 0 180)
			(layer "F.SilkS")
			(hide yes)
			(effects
				(font
					(size 1.27 1.27)
				)
			)
		)
		(property "Value" "0R5J-5-GP"
			(at 0 -8.9535 180)
			(unlocked yes)
			(layer "F.Fab")
			(hide yes)
			(effects
				(font
					(size 1.27 1.016)
					(thickness 0.1524)
				)
			)
		)
		(property "Device Type" "R805H24"
			(at 0 -10.6299 180)
			(unlocked yes)
			(layer "F.Fab")
			(hide yes)
			(effects
				(font
					(size 1.27 1.016)
					(thickness 0.1524)
				)
			)
		)
		(duplicate_pad_numbers_are_jumpers no)
		(fp_line
			(start 0.889 1.7018)
			(end 0.889 -0.508)
			(stroke
				(width 0.1524)
				(type default)
			)
			(layer "F.SilkS")
		)
		(fp_line
			(start 0.889 -1.7018)
			(end 0.889 -0.381)
			(stroke
				(width 0.1524)
				(type default)
			)
			(layer "F.SilkS")
		)
		(fp_line
			(start 0.889 -1.7018)
			(end -0.889 -1.7018)
			(stroke
				(width 0.1524)
				(type default)
			)
			(layer "F.SilkS")
		)
		(fp_line
			(start -0.889 1.7018)
			(end 0.889 1.7018)
			(stroke
				(width 0.1524)
				(type default)
			)
			(layer "F.SilkS")
		)
		(fp_line
			(start -0.889 0.0762)
			(end -0.889 1.7018)
			(stroke
				(width 0.1524)
				(type default)
			)
			(layer "F.SilkS")
		)
		(fp_line
			(start -0.889 -1.7018)
			(end -0.889 0.2794)
			(stroke
				(width 0.1524)
				(type default)
			)
			(layer "F.SilkS")
		)
		(fp_poly
			(pts
				(xy 0.9652 -1.778) (xy 0.9652 1.778) (xy -0.9652 1.778) (xy -0.9652 -1.778)
			)
			(stroke
				(width 0)
				(type default)
			)
			(fill no)
			(layer "F.CrtYd")
		)
		(fp_rect
			(start -0.9652 1.778)
			(end 0.9652 -1.778)
			(stroke
				(width 0)
				(type default)
			)
			(fill no)
			(layer "F.Fab")
		)
		(pad "1" smd rect
			(at 0 -0.9652 180)
			(size 1.397 1.143)
			(layers "F.Cu" "F.Mask" "F.Paste")
			(net "P1V2_STBY")
		)
		(pad "2" smd rect
			(at 0 0.9652 180)
			(size 1.397 1.143)
			(layers "F.Cu" "F.Mask" "F.Paste")
			(net "TPS74801_P1V2_STBY_OUT")
		)
	)
	(footprint ""
		(layer "F.Cu")
		(at 76.498704 -141.633194 90)
		(property "Reference" "R129"
			(at 0 0 90)
			(layer "F.SilkS")
			(hide yes)
			(effects
				(font
					(size 1.27 1.27)
				)
			)
		)
		(property "Value" "0R2J-2-GP"
			(at 0.064008 -3.993896 90)
			(unlocked yes)
			(layer "F.Fab")
			(hide yes)
			(effects
				(font
					(size 1.016 1.016)
					(thickness 0.1524)
				)
			)
		)
		(property "Device Type" "R402H16"
			(at 0.064008 -5.517896 90)
			(unlocked yes)
			(layer "F.Fab")
			(hide yes)
			(effects
				(font
					(size 1.016 1.016)
					(thickness 0.1524)
				)
			)
		)
		(duplicate_pad_numbers_are_jumpers no)
		(fp_line
			(start 0.508 -0.9398)
			(end -0.508 -0.9398)
			(stroke
				(width 0.1524)
				(type default)
			)
			(layer "F.SilkS")
		)
		(fp_line
			(start -0.508 -0.9398)
			(end -0.508 0.9398)
			(stroke
				(width 0.1524)
				(type default)
			)
			(layer "F.SilkS")
		)
		(fp_rect
			(start -0.508 0.9398)
			(end 0.508 -0.9398)
			(stroke
				(width 0)
				(type default)
			)
			(fill no)
			(layer "F.CrtYd")
		)
		(fp_rect
			(start -0.508 0.9398)
			(end 0.508 -0.9398)
			(stroke
				(width 0)
				(type default)
			)
			(fill no)
			(layer "F.Fab")
		)
		(pad "1" smd custom
			(at 0 -0.4445 90)
			(size 0.1397 0.1397)
			(layers "F.Cu" "F.Mask" "F.Paste")
			(net "I2C_EXP_RMT_SCL")
			(options
				(clearance outline)
				(anchor circle)
			)
			(primitives
				(gr_poly
					(pts
						(arc
							(start -0.1778 -0.2794)
							(mid -0.249642 -0.249642)
							(end -0.2794 -0.1778)
						)
						(arc
							(start -0.2794 0.1778)
							(mid -0.249642 0.249642)
							(end -0.1778 0.2794)
						)
						(arc
							(start 0.1778 0.2794)
							(mid 0.249642 0.249642)
							(end 0.2794 0.1778)
						)
						(arc
							(start 0.2794 -0.1778)
							(mid 0.249642 -0.249642)
							(end 0.1778 -0.2794)
						)
					)
					(width 0)
					(fill yes)
				)
			)
		)
		(pad "2" smd custom
			(at 0 0.4445 90)
			(size 0.1397 0.1397)
			(layers "F.Cu" "F.Mask" "F.Paste")
			(net "I2C_EXP_RMT_SCL_R")
			(options
				(clearance outline)
				(anchor circle)
			)
			(primitives
				(gr_poly
					(pts
						(arc
							(start -0.1778 -0.2794)
							(mid -0.249642 -0.249642)
							(end -0.2794 -0.1778)
						)
						(arc
							(start -0.2794 0.1778)
							(mid -0.249642 0.249642)
							(end -0.1778 0.2794)
						)
						(arc
							(start 0.1778 0.2794)
							(mid 0.249642 0.249642)
							(end 0.2794 0.1778)
						)
						(arc
							(start 0.2794 -0.1778)
							(mid 0.249642 -0.249642)
							(end 0.1778 -0.2794)
						)
					)
					(width 0)
					(fill yes)
				)
			)
		)
	)
	(footprint ""
		(layer "F.Cu")
		(at 33.7693 -152.2095 -90)
		(property "Reference" "R333"
			(at 0 0 270)
			(layer "F.SilkS")
			(hide yes)
			(effects
				(font
					(size 1.27 1.27)
				)
			)
		)
		(property "Value" "0R2J-2-GP"
			(at 0.064008 -3.993896 270)
			(unlocked yes)
			(layer "F.Fab")
			(hide yes)
			(effects
				(font
					(size 1.016 1.016)
					(thickness 0.1524)
				)
			)
		)
		(property "Device Type" "R402H16"
			(at 0.064008 -5.517896 270)
			(unlocked yes)
			(layer "F.Fab")
			(hide yes)
			(effects
				(font
					(size 1.016 1.016)
					(thickness 0.1524)
				)
			)
		)
		(duplicate_pad_numbers_are_jumpers no)
		(fp_line
			(start -0.508 -0.9398)
			(end -0.508 0.9398)
			(stroke
				(width 0.1524)
				(type default)
			)
			(layer "F.SilkS")
		)
		(fp_line
			(start 0.508 -0.9398)
			(end -0.508 -0.9398)
			(stroke
				(width 0.1524)
				(type default)
			)
			(layer "F.SilkS")
		)
		(fp_rect
			(start -0.508 0.9398)
			(end 0.508 -0.9398)
			(stroke
				(width 0)
				(type default)
			)
			(fill no)
			(layer "F.CrtYd")
		)
		(fp_rect
			(start -0.508 0.9398)
			(end 0.508 -0.9398)
			(stroke
				(width 0)
				(type default)
			)
			(fill no)
			(layer "F.Fab")
		)
		(pad "1" smd custom
			(at 0 -0.4445 270)
			(size 0.1397 0.1397)
			(layers "F.Cu" "F.Mask" "F.Paste")
			(net "THROTTLE_N")
			(options
				(clearance outline)
				(anchor circle)
			)
			(primitives
				(gr_poly
					(pts
						(arc
							(start -0.1778 -0.2794)
							(mid -0.249642 -0.249642)
							(end -0.2794 -0.1778)
						)
						(arc
							(start -0.2794 0.1778)
							(mid -0.249642 0.249642)
							(end -0.1778 0.2794)
						)
						(arc
							(start 0.1778 0.2794)
							(mid 0.249642 0.249642)
							(end 0.2794 0.1778)
						)
						(arc
							(start 0.2794 -0.1778)
							(mid 0.249642 -0.249642)
							(end 0.1778 -0.2794)
						)
					)
					(width 0)
					(fill yes)
				)
			)
		)
		(pad "2" smd custom
			(at 0 0.4445 270)
			(size 0.1397 0.1397)
			(layers "F.Cu" "F.Mask" "F.Paste")
			(net "COMP_FAST_THROTTLE_N")
			(options
				(clearance outline)
				(anchor circle)
			)
			(primitives
				(gr_poly
					(pts
						(arc
							(start -0.1778 -0.2794)
							(mid -0.249642 -0.249642)
							(end -0.2794 -0.1778)
						)
						(arc
							(start -0.2794 0.1778)
							(mid -0.249642 0.249642)
							(end -0.1778 0.2794)
						)
						(arc
							(start 0.1778 0.2794)
							(mid 0.249642 0.249642)
							(end 0.2794 0.1778)
						)
						(arc
							(start 0.2794 -0.1778)
							(mid 0.249642 -0.249642)
							(end 0.1778 -0.2794)
						)
					)
					(width 0)
					(fill yes)
				)
			)
		)
	)
	(footprint ""
		(layer "F.Cu")
		(at 189.4078 -48.4378 180)
		(property "Reference" "R646"
			(at 0 0 180)
			(layer "F.SilkS")
			(hide yes)
			(effects
				(font
					(size 1.27 1.27)
				)
			)
		)
		(property "Value" "10KR2F-2-GP"
			(at 0.064008 -3.993896 180)
			(unlocked yes)
			(layer "F.Fab")
			(hide yes)
			(effects
				(font
					(size 1.016 1.016)
					(thickness 0.1524)
				)
			)
		)
		(property "Device Type" "R402H16"
			(at 0.064008 -5.517896 180)
			(unlocked yes)
			(layer "F.Fab")
			(hide yes)
			(effects
				(font
					(size 1.016 1.016)
					(thickness 0.1524)
				)
			)
		)
		(duplicate_pad_numbers_are_jumpers no)
		(fp_line
			(start 0.508 -0.9398)
			(end -0.508 -0.9398)
			(stroke
				(width 0.1524)
				(type default)
			)
			(layer "F.SilkS")
		)
		(fp_line
			(start -0.508 -0.9398)
			(end -0.508 0.9398)
			(stroke
				(width 0.1524)
				(type default)
			)
			(layer "F.SilkS")
		)
		(fp_rect
			(start -0.508 0.9398)
			(end 0.508 -0.9398)
			(stroke
				(width 0)
				(type default)
			)
			(fill no)
			(layer "F.CrtYd")
		)
		(fp_rect
			(start -0.508 0.9398)
			(end 0.508 -0.9398)
			(stroke
				(width 0)
				(type default)
			)
			(fill no)
			(layer "F.Fab")
		)
		(pad "1" smd custom
			(at 0 -0.4445 180)
			(size 0.1397 0.1397)
			(layers "F.Cu" "F.Mask" "F.Paste")
			(net "P1V8")
			(options
				(clearance outline)
				(anchor circle)
			)
			(primitives
				(gr_poly
					(pts
						(arc
							(start -0.1778 -0.2794)
							(mid -0.249642 -0.249642)
							(end -0.2794 -0.1778)
						)
						(arc
							(start -0.2794 0.1778)
							(mid -0.249642 0.249642)
							(end -0.1778 0.2794)
						)
						(arc
							(start 0.1778 0.2794)
							(mid 0.249642 0.249642)
							(end 0.2794 0.1778)
						)
						(arc
							(start 0.2794 -0.1778)
							(mid 0.249642 -0.249642)
							(end 0.1778 -0.2794)
						)
					)
					(width 0)
					(fill yes)
				)
			)
		)
		(pad "2" smd custom
			(at 0 0.4445 180)
			(size 0.1397 0.1397)
			(layers "F.Cu" "F.Mask" "F.Paste")
			(net "LSI_JTAG_EN_N")
			(options
				(clearance outline)
				(anchor circle)
			)
			(primitives
				(gr_poly
					(pts
						(arc
							(start -0.1778 -0.2794)
							(mid -0.249642 -0.249642)
							(end -0.2794 -0.1778)
						)
						(arc
							(start -0.2794 0.1778)
							(mid -0.249642 0.249642)
							(end -0.1778 0.2794)
						)
						(arc
							(start 0.1778 0.2794)
							(mid 0.249642 0.249642)
							(end 0.2794 0.1778)
						)
						(arc
							(start 0.2794 -0.1778)
							(mid 0.249642 -0.249642)
							(end 0.1778 -0.2794)
						)
					)
					(width 0)
					(fill yes)
				)
			)
		)
	)
	(footprint ""
		(layer "F.Cu")
		(at 157.099 -120.142 -90)
		(property "Reference" "C215"
			(at 0 0 270)
			(layer "F.SilkS")
			(hide yes)
			(effects
				(font
					(size 1.27 1.27)
				)
			)
		)
		(property "Value" "SC10U6D3V5KX-4GP"
			(at -0.0762 -6.1214 270)
			(unlocked yes)
			(layer "F.Fab")
			(hide yes)
			(effects
				(font
					(size 1.016 1.016)
					(thickness 0.1524)
				)
			)
		)
		(property "Device Type" "C805H58"
			(at -0.0762 -8.1534 270)
			(unlocked yes)
			(layer "F.Fab")
			(hide yes)
			(effects
				(font
					(size 1.016 1.016)
					(thickness 0.1524)
				)
			)
		)
		(duplicate_pad_numbers_are_jumpers no)
		(fp_line
			(start 0.635 0)
			(end -0.635 0)
			(stroke
				(width 0.508)
				(type default)
			)
			(layer "F.SilkS")
		)
		(fp_rect
			(start -0.9652 1.778)
			(end 0.9652 -1.778)
			(stroke
				(width 0)
				(type default)
			)
			(fill no)
			(layer "F.CrtYd")
		)
		(fp_poly
			(pts
				(xy -0.9652 -1.778) (xy 0.9652 -1.778) (xy 0.9652 1.778) (xy -0.9652 1.778)
			)
			(stroke
				(width 0)
				(type default)
			)
			(fill no)
			(layer "F.Fab")
		)
		(pad "1" smd rect
			(at 0 -0.9652 270)
			(size 1.397 1.143)
			(layers "F.Cu" "F.Mask" "F.Paste")
			(net "P1V8_STBY")
		)
		(pad "2" smd rect
			(at 0 0.9652 270)
			(size 1.397 1.143)
			(layers "F.Cu" "F.Mask" "F.Paste")
			(net "GND")
		)
	)
	(footprint ""
		(layer "F.Cu")
		(at 98.878644 -159.532574 -90)
		(property "Reference" "R20"
			(at 0 0 270)
			(layer "F.SilkS")
			(hide yes)
			(effects
				(font
					(size 1.27 1.27)
				)
			)
		)
		(property "Value" "4K7R2F-GP"
			(at 0.064008 -3.993896 270)
			(unlocked yes)
			(layer "F.Fab")
			(hide yes)
			(effects
				(font
					(size 1.016 1.016)
					(thickness 0.1524)
				)
			)
		)
		(property "Device Type" "R402H16"
			(at 0.064008 -5.517896 270)
			(unlocked yes)
			(layer "F.Fab")
			(hide yes)
			(effects
				(font
					(size 1.016 1.016)
					(thickness 0.1524)
				)
			)
		)
		(duplicate_pad_numbers_are_jumpers no)
		(fp_line
			(start -0.508 -0.9398)
			(end -0.508 0.9398)
			(stroke
				(width 0.1524)
				(type default)
			)
			(layer "F.SilkS")
		)
		(fp_line
			(start 0.508 -0.9398)
			(end -0.508 -0.9398)
			(stroke
				(width 0.1524)
				(type default)
			)
			(layer "F.SilkS")
		)
		(fp_rect
			(start -0.508 0.9398)
			(end 0.508 -0.9398)
			(stroke
				(width 0)
				(type default)
			)
			(fill no)
			(layer "F.CrtYd")
		)
		(fp_rect
			(start -0.508 0.9398)
			(end 0.508 -0.9398)
			(stroke
				(width 0)
				(type default)
			)
			(fill no)
			(layer "F.Fab")
		)
		(pad "1" smd custom
			(at 0 -0.4445 270)
			(size 0.1397 0.1397)
			(layers "F.Cu" "F.Mask" "F.Paste")
			(net "P3V3_STBY")
			(options
				(clearance outline)
				(anchor circle)
			)
			(primitives
				(gr_poly
					(pts
						(arc
							(start -0.1778 -0.2794)
							(mid -0.249642 -0.249642)
							(end -0.2794 -0.1778)
						)
						(arc
							(start -0.2794 0.1778)
							(mid -0.249642 0.249642)
							(end -0.1778 0.2794)
						)
						(arc
							(start 0.1778 0.2794)
							(mid 0.249642 0.249642)
							(end 0.2794 0.1778)
						)
						(arc
							(start 0.2794 -0.1778)
							(mid 0.249642 -0.249642)
							(end 0.1778 -0.2794)
						)
					)
					(width 0)
					(fill yes)
				)
			)
		)
		(pad "2" smd custom
			(at 0 0.4445 270)
			(size 0.1397 0.1397)
			(layers "F.Cu" "F.Mask" "F.Paste")
			(net "VBUS_DET")
			(options
				(clearance outline)
				(anchor circle)
			)
			(primitives
				(gr_poly
					(pts
						(arc
							(start -0.1778 -0.2794)
							(mid -0.249642 -0.249642)
							(end -0.2794 -0.1778)
						)
						(arc
							(start -0.2794 0.1778)
							(mid -0.249642 0.249642)
							(end -0.1778 0.2794)
						)
						(arc
							(start 0.1778 0.2794)
							(mid 0.249642 0.249642)
							(end 0.2794 0.1778)
						)
						(arc
							(start 0.2794 -0.1778)
							(mid 0.249642 -0.249642)
							(end 0.1778 -0.2794)
						)
					)
					(width 0)
					(fill yes)
				)
			)
		)
	)
	(footprint ""
		(layer "F.Cu")
		(at 94.488 -30.734 90)
		(property "Reference" "C22"
			(at 0 0 90)
			(layer "F.SilkS")
			(hide yes)
			(effects
				(font
					(size 1.27 1.27)
				)
			)
		)
		(property "Value" "SC1U16V3KX-5GP"
			(at 0 -2.8194 90)
			(unlocked yes)
			(layer "F.Fab")
			(hide yes)
			(effects
				(font
					(size 1.016 1.016)
					(thickness 0.1524)
				)
			)
		)
		(property "Device Type" "C603H36"
			(at 0 -4.3434 90)
			(unlocked yes)
			(layer "F.Fab")
			(hide yes)
			(effects
				(font
					(size 1.016 1.016)
					(thickness 0.1524)
				)
			)
		)
		(duplicate_pad_numbers_are_jumpers no)
		(fp_line
			(start 0.508 0)
			(end -0.508 0)
			(stroke
				(width 0.2032)
				(type default)
			)
			(layer "F.SilkS")
		)
		(fp_rect
			(start -0.5842 1.3335)
			(end 0.5842 -1.3335)
			(stroke
				(width 0)
				(type default)
			)
			(fill no)
			(layer "F.CrtYd")
		)
		(fp_rect
			(start -0.5842 1.3335)
			(end 0.5842 -1.3335)
			(stroke
				(width 0)
				(type default)
			)
			(fill no)
			(layer "F.Fab")
		)
		(pad "1" smd custom
			(at 0 -0.762 90)
			(size 0.2159 0.2159)
			(layers "F.Cu" "F.Mask" "F.Paste")
			(net "P5V_USB")
			(options
				(clearance outline)
				(anchor circle)
			)
			(primitives
				(gr_poly
					(pts
						(arc
							(start -0.3302 -0.4318)
							(mid -0.402042 -0.402042)
							(end -0.4318 -0.3302)
						)
						(arc
							(start -0.4318 0.3302)
							(mid -0.402042 0.402042)
							(end -0.3302 0.4318)
						)
						(arc
							(start 0.3302 0.4318)
							(mid 0.402042 0.402042)
							(end 0.4318 0.3302)
						)
						(arc
							(start 0.4318 -0.3302)
							(mid 0.402042 -0.402042)
							(end 0.3302 -0.4318)
						)
					)
					(width 0)
					(fill yes)
				)
			)
		)
		(pad "2" smd custom
			(at 0 0.762 90)
			(size 0.2159 0.2159)
			(layers "F.Cu" "F.Mask" "F.Paste")
			(net "GND")
			(options
				(clearance outline)
				(anchor circle)
			)
			(primitives
				(gr_poly
					(pts
						(arc
							(start -0.3302 -0.4318)
							(mid -0.402042 -0.402042)
							(end -0.4318 -0.3302)
						)
						(arc
							(start -0.4318 0.3302)
							(mid -0.402042 0.402042)
							(end -0.3302 0.4318)
						)
						(arc
							(start 0.3302 0.4318)
							(mid 0.402042 0.402042)
							(end 0.4318 0.3302)
						)
						(arc
							(start 0.4318 -0.3302)
							(mid 0.402042 -0.402042)
							(end 0.3302 -0.4318)
						)
					)
					(width 0)
					(fill yes)
				)
			)
		)
	)
	(footprint ""
		(layer "F.Cu")
		(at 182.340504 -150.883366 90)
		(property "Reference" "R465"
			(at 0 0 90)
			(layer "F.SilkS")
			(hide yes)
			(effects
				(font
					(size 1.27 1.27)
				)
			)
		)
		(property "Value" "2K2R2F-GP"
			(at 0.064008 -3.993896 90)
			(unlocked yes)
			(layer "F.Fab")
			(hide yes)
			(effects
				(font
					(size 1.016 1.016)
					(thickness 0.1524)
				)
			)
		)
		(property "Device Type" "R402H16"
			(at 0.064008 -5.517896 90)
			(unlocked yes)
			(layer "F.Fab")
			(hide yes)
			(effects
				(font
					(size 1.016 1.016)
					(thickness 0.1524)
				)
			)
		)
		(duplicate_pad_numbers_are_jumpers no)
		(fp_line
			(start 0.508 -0.9398)
			(end -0.508 -0.9398)
			(stroke
				(width 0.1524)
				(type default)
			)
			(layer "F.SilkS")
		)
		(fp_line
			(start -0.508 -0.9398)
			(end -0.508 0.9398)
			(stroke
				(width 0.1524)
				(type default)
			)
			(layer "F.SilkS")
		)
		(fp_rect
			(start -0.508 0.9398)
			(end 0.508 -0.9398)
			(stroke
				(width 0)
				(type default)
			)
			(fill no)
			(layer "F.CrtYd")
		)
		(fp_rect
			(start -0.508 0.9398)
			(end 0.508 -0.9398)
			(stroke
				(width 0)
				(type default)
			)
			(fill no)
			(layer "F.Fab")
		)
		(pad "1" smd custom
			(at 0 -0.4445 90)
			(size 0.1397 0.1397)
			(layers "F.Cu" "F.Mask" "F.Paste")
			(net "P5V_EN_R")
			(options
				(clearance outline)
				(anchor circle)
			)
			(primitives
				(gr_poly
					(pts
						(arc
							(start -0.1778 -0.2794)
							(mid -0.249642 -0.249642)
							(end -0.2794 -0.1778)
						)
						(arc
							(start -0.2794 0.1778)
							(mid -0.249642 0.249642)
							(end -0.1778 0.2794)
						)
						(arc
							(start 0.1778 0.2794)
							(mid 0.249642 0.249642)
							(end 0.2794 0.1778)
						)
						(arc
							(start 0.2794 -0.1778)
							(mid 0.249642 -0.249642)
							(end 0.1778 -0.2794)
						)
					)
					(width 0)
					(fill yes)
				)
			)
		)
		(pad "2" smd custom
			(at 0 0.4445 90)
			(size 0.1397 0.1397)
			(layers "F.Cu" "F.Mask" "F.Paste")
			(net "GND")
			(options
				(clearance outline)
				(anchor circle)
			)
			(primitives
				(gr_poly
					(pts
						(arc
							(start -0.1778 -0.2794)
							(mid -0.249642 -0.249642)
							(end -0.2794 -0.1778)
						)
						(arc
							(start -0.2794 0.1778)
							(mid -0.249642 0.249642)
							(end -0.1778 0.2794)
						)
						(arc
							(start 0.1778 0.2794)
							(mid 0.249642 0.249642)
							(end 0.2794 0.1778)
						)
						(arc
							(start 0.2794 -0.1778)
							(mid 0.249642 -0.249642)
							(end 0.1778 -0.2794)
						)
					)
					(width 0)
					(fill yes)
				)
			)
		)
	)
)
